(kicad_pcb
	(version 20241229)
	(generator "pcbnew")
	(generator_version "9.0")
	(general
		(thickness 1.59)
		(legacy_teardrops no)
	)
	(paper "A3")
	(title_block
		(title "usb-c-power-adapter")
		(date "2025-06-24")
		(rev "1.1.2")
		(company "Antmicro")
		(comment 9 "footprints 93-98 of 122")
	)
	(layers
		(0 "F.Cu" signal)
		(4 "In1.Cu" signal)
		(6 "In2.Cu" signal)
		(2 "B.Cu" signal)
		(9 "F.Adhes" user "F.Adhesive")
		(11 "B.Adhes" user "B.Adhesive")
		(13 "F.Paste" user)
		(15 "B.Paste" user)
		(5 "F.SilkS" user "F.Silkscreen")
		(7 "B.SilkS" user "B.Silkscreen")
		(1 "F.Mask" user)
		(3 "B.Mask" user)
		(17 "Dwgs.User" user "User.Drawings")
		(19 "Cmts.User" user "User.Comments")
		(21 "Eco1.User" user "User.Eco1")
		(23 "Eco2.User" user "User.Eco2")
		(25 "Edge.Cuts" user)
		(27 "Margin" user)
		(31 "F.CrtYd" user "F.Courtyard")
		(29 "B.CrtYd" user "B.Courtyard")
		(35 "F.Fab" user)
		(33 "B.Fab" user)
	)
	(footprint "antmicro-footprints:C_0805_2012Metric"
		(layer "B.Cu")
		(at 96.15 93.05 -90)
		(descr "Capacitor SMD 0805")
		(tags "capacitor SMD 0805")
		(property "Reference" "C38"
			(at -21.295 12.074 180)
			(layer "B.SilkS")
			(effects
				(font
					(size 0.7 0.7)
					(thickness 0.15)
				)
				(justify left bottom mirror)
			)
		)
		(property "Value" "C_22u_25V_0805"
			(at -2.055717 -1.963152 90)
			(layer "B.Fab")
			(effects
				(font
					(size 0.7 0.7)
					(thickness 0.15)
				)
				(justify left bottom mirror)
			)
		)
		(property "Datasheet" "https://product.samsungsem.com/mlcc/CL21A226MAYNNN.do"
			(at 0 0 270)
			(layer "F.Fab")
			(hide yes)
			(effects
				(font
					(size 1.27 1.27)
					(thickness 0.15)
				)
			)
		)
		(property "Description" "SMT Multilayer Ceramic Capacitor, 22uF, +/-20%, 25V, X5R, 0805 [2012 Metric]"
			(at 0 0 270)
			(layer "F.Fab")
			(hide yes)
			(effects
				(font
					(size 1.27 1.27)
					(thickness 0.15)
				)
			)
		)
		(property "MPN" "CL21A226MAYNNNE"
			(at 0 0 270)
			(unlocked yes)
			(layer "B.Fab")
			(hide yes)
			(effects
				(font
					(size 1 1)
					(thickness 0.15)
				)
				(justify mirror)
			)
		)
		(property "Manufacturer" "Samsung Electro-Mechanics"
			(at 0 0 270)
			(unlocked yes)
			(layer "B.Fab")
			(hide yes)
			(effects
				(font
					(size 1 1)
					(thickness 0.15)
				)
				(justify mirror)
			)
		)
		(property "License" "Apache-2.0"
			(at 0 0 270)
			(unlocked yes)
			(layer "B.Fab")
			(hide yes)
			(effects
				(font
					(size 1 1)
					(thickness 0.15)
				)
				(justify mirror)
			)
		)
		(property "Author" "Antmicro"
			(at 0 0 270)
			(unlocked yes)
			(layer "B.Fab")
			(hide yes)
			(effects
				(font
					(size 1 1)
					(thickness 0.15)
				)
				(justify mirror)
			)
		)
		(property "Val" "22u"
			(at 0 0 270)
			(unlocked yes)
			(layer "B.Fab")
			(hide yes)
			(effects
				(font
					(size 1 1)
					(thickness 0.15)
				)
				(justify mirror)
			)
		)
		(property "Voltage" "25V"
			(at 0 0 270)
			(unlocked yes)
			(layer "B.Fab")
			(hide yes)
			(effects
				(font
					(size 1 1)
					(thickness 0.15)
				)
				(justify mirror)
			)
		)
		(property "Dielectric" "X5R"
			(at 0 0 270)
			(unlocked yes)
			(layer "B.Fab")
			(hide yes)
			(effects
				(font
					(size 1 1)
					(thickness 0.15)
				)
				(justify mirror)
			)
		)
		(property "Public" "False"
			(at 0 0 270)
			(unlocked yes)
			(layer "B.Fab")
			(hide yes)
			(effects
				(font
					(size 1 1)
					(thickness 0.15)
				)
				(justify mirror)
			)
		)
		(sheetname "/DC-DC Converters/")
		(sheetfile "dc-dc_converters.kicad_sch")
		(attr smd)
		(fp_line
			(start 0.3 0.7)
			(end -0.3 0.7)
			(stroke
				(width 0.15)
				(type solid)
			)
			(layer "B.SilkS")
		)
		(fp_line
			(start 0.3 -0.7)
			(end -0.3 -0.7)
			(stroke
				(width 0.15)
				(type solid)
			)
			(layer "B.SilkS")
		)
		(fp_rect
			(start 1.95 0.9)
			(end -1.95 -0.9)
			(stroke
				(width 0.05)
				(type default)
			)
			(fill no)
			(layer "B.CrtYd")
		)
		(fp_rect
			(start -0.95 0.675)
			(end 0.95 -0.675)
			(stroke
				(width 0.15)
				(type solid)
			)
			(fill no)
			(layer "B.Fab")
		)
		(pad "1" smd roundrect
			(at -1.1 0 270)
			(size 1.2 1.3)
			(layers "B.Cu" "B.Mask" "B.Paste")
			(roundrect_rratio 0.25)
			(net 2 "GND")
			(pintype "passive")
		)
		(pad "2" smd roundrect
			(at 1.1 0 270)
			(size 1.2 1.3)
			(layers "B.Cu" "B.Mask" "B.Paste")
			(roundrect_rratio 0.25)
			(net 5 "+12V")
			(pintype "passive")
		)
	)
	(footprint "antmicro-footprints:R_0402_1005Metric"
		(layer "B.Cu")
		(at 88.351 86.7 90)
		(descr "Resistor SMD 0402")
		(tags "resistor SMD 0402")
		(property "Reference" "R10"
			(at 1.083 3.051 90)
			(layer "B.SilkS")
			(effects
				(font
					(size 0.7 0.7)
					(thickness 0.15)
				)
				(justify left bottom mirror)
			)
		)
		(property "Value" "R_100k_0402"
			(at -1.011843 -1.772047 90)
			(layer "B.Fab")
			(effects
				(font
					(size 0.7 0.7)
					(thickness 0.15)
				)
				(justify right bottom mirror)
			)
		)
		(property "Datasheet" "https://www.bourns.com/docs/product-datasheets/cr.pdf"
			(at 0 0 90)
			(layer "F.Fab")
			(hide yes)
			(effects
				(font
					(size 1.27 1.27)
					(thickness 0.15)
				)
			)
		)
		(property "Description" "SMD Chip Resistor, 100 kohm, ± 1%, 62.5 mW, 0402 [1005 Metric], Thick Film, General Purpose"
			(at 0 0 90)
			(layer "F.Fab")
			(hide yes)
			(effects
				(font
					(size 1.27 1.27)
					(thickness 0.15)
				)
			)
		)
		(property "MPN" "CR0402-FX-1003GLF"
			(at 0 0 90)
			(unlocked yes)
			(layer "B.Fab")
			(hide yes)
			(effects
				(font
					(size 1 1)
					(thickness 0.15)
				)
				(justify mirror)
			)
		)
		(property "Manufacturer" "Bourns"
			(at 0 0 90)
			(unlocked yes)
			(layer "B.Fab")
			(hide yes)
			(effects
				(font
					(size 1 1)
					(thickness 0.15)
				)
				(justify mirror)
			)
		)
		(property "License" "Apache-2.0"
			(at 0 0 90)
			(unlocked yes)
			(layer "B.Fab")
			(hide yes)
			(effects
				(font
					(size 1 1)
					(thickness 0.15)
				)
				(justify mirror)
			)
		)
		(property "Author" "Antmicro"
			(at 0 0 90)
			(unlocked yes)
			(layer "B.Fab")
			(hide yes)
			(effects
				(font
					(size 1 1)
					(thickness 0.15)
				)
				(justify mirror)
			)
		)
		(property "Val" "100k"
			(at 0 0 90)
			(unlocked yes)
			(layer "B.Fab")
			(hide yes)
			(effects
				(font
					(size 1 1)
					(thickness 0.15)
				)
				(justify mirror)
			)
		)
		(property "Tolerance" "1%"
			(at 0 0 90)
			(unlocked yes)
			(layer "B.Fab")
			(hide yes)
			(effects
				(font
					(size 1 1)
					(thickness 0.15)
				)
				(justify mirror)
			)
		)
		(sheetname "/DC-DC Converters/")
		(sheetfile "dc-dc_converters.kicad_sch")
		(attr smd)
		(fp_rect
			(start -0.925 0.47)
			(end 0.925 -0.47)
			(stroke
				(width 0.05)
				(type default)
			)
			(fill no)
			(layer "B.CrtYd")
		)
		(fp_rect
			(start -0.5 0.25)
			(end 0.5 -0.25)
			(stroke
				(width 0.15)
				(type solid)
			)
			(fill no)
			(layer "B.Fab")
		)
		(pad "1" smd roundrect
			(at -0.48 0 90)
			(size 0.59 0.64)
			(layers "B.Cu" "B.Mask" "B.Paste")
			(roundrect_rratio 0.25)
			(net 47 "Net-(U3-EN)")
			(pintype "passive")
		)
		(pad "2" smd roundrect
			(at 0.48 0 90)
			(size 0.59 0.64)
			(layers "B.Cu" "B.Mask" "B.Paste")
			(roundrect_rratio 0.25)
			(net 5 "+12V")
			(pintype "passive")
		)
	)
	(footprint "antmicro-footprints:R_0402_1005Metric"
		(layer "B.Cu")
		(at 85.85 84.25 180)
		(descr "Resistor SMD 0402")
		(tags "resistor SMD 0402")
		(property "Reference" "R11"
			(at -0.826 -0.4 0)
			(layer "B.SilkS")
			(effects
				(font
					(size 0.7 0.7)
					(thickness 0.15)
				)
				(justify right bottom mirror)
			)
		)
		(property "Value" "R_100k_0402"
			(at -1.011843 -1.772047 0)
			(layer "B.Fab")
			(effects
				(font
					(size 0.7 0.7)
					(thickness 0.15)
				)
				(justify left bottom mirror)
			)
		)
		(property "Datasheet" "https://www.bourns.com/docs/product-datasheets/cr.pdf"
			(at 0 0 180)
			(layer "F.Fab")
			(hide yes)
			(effects
				(font
					(size 1.27 1.27)
					(thickness 0.15)
				)
			)
		)
		(property "Description" "SMD Chip Resistor, 100 kohm, ± 1%, 62.5 mW, 0402 [1005 Metric], Thick Film, General Purpose"
			(at 0 0 180)
			(layer "F.Fab")
			(hide yes)
			(effects
				(font
					(size 1.27 1.27)
					(thickness 0.15)
				)
			)
		)
		(property "MPN" "CR0402-FX-1003GLF"
			(at 0 0 180)
			(unlocked yes)
			(layer "B.Fab")
			(hide yes)
			(effects
				(font
					(size 1 1)
					(thickness 0.15)
				)
				(justify mirror)
			)
		)
		(property "Manufacturer" "Bourns"
			(at 0 0 180)
			(unlocked yes)
			(layer "B.Fab")
			(hide yes)
			(effects
				(font
					(size 1 1)
					(thickness 0.15)
				)
				(justify mirror)
			)
		)
		(property "License" "Apache-2.0"
			(at 0 0 180)
			(unlocked yes)
			(layer "B.Fab")
			(hide yes)
			(effects
				(font
					(size 1 1)
					(thickness 0.15)
				)
				(justify mirror)
			)
		)
		(property "Author" "Antmicro"
			(at 0 0 180)
			(unlocked yes)
			(layer "B.Fab")
			(hide yes)
			(effects
				(font
					(size 1 1)
					(thickness 0.15)
				)
				(justify mirror)
			)
		)
		(property "Val" "100k"
			(at 0 0 180)
			(unlocked yes)
			(layer "B.Fab")
			(hide yes)
			(effects
				(font
					(size 1 1)
					(thickness 0.15)
				)
				(justify mirror)
			)
		)
		(property "Tolerance" "1%"
			(at 0 0 180)
			(unlocked yes)
			(layer "B.Fab")
			(hide yes)
			(effects
				(font
					(size 1 1)
					(thickness 0.15)
				)
				(justify mirror)
			)
		)
		(sheetname "/DC-DC Converters/")
		(sheetfile "dc-dc_converters.kicad_sch")
		(attr smd)
		(fp_rect
			(start -0.925 0.47)
			(end 0.925 -0.47)
			(stroke
				(width 0.05)
				(type default)
			)
			(fill no)
			(layer "B.CrtYd")
		)
		(fp_rect
			(start -0.5 0.25)
			(end 0.5 -0.25)
			(stroke
				(width 0.15)
				(type solid)
			)
			(fill no)
			(layer "B.Fab")
		)
		(pad "1" smd roundrect
			(at -0.48 0 180)
			(size 0.59 0.64)
			(layers "B.Cu" "B.Mask" "B.Paste")
			(roundrect_rratio 0.25)
			(net 9 "Net-(U4-EN)")
			(pintype "passive")
		)
		(pad "2" smd roundrect
			(at 0.48 0 180)
			(size 0.59 0.64)
			(layers "B.Cu" "B.Mask" "B.Paste")
			(roundrect_rratio 0.25)
			(net 5 "+12V")
			(pintype "passive")
		)
	)
	(footprint "antmicro-footprints:F_1206_3216Metric"
		(layer "B.Cu")
		(at 85.8 95.7 -90)
		(property "Reference" "F1"
			(at 3.65 0.724 180)
			(layer "B.SilkS")
			(effects
				(font
					(size 0.7 0.7)
					(thickness 0.15)
				)
				(justify right bottom mirror)
			)
		)
		(property "Value" "F_7A_1206"
			(at 0 -2 90)
			(layer "B.Fab")
			(effects
				(font
					(size 0.7 0.7)
					(thickness 0.15)
				)
				(justify left bottom mirror)
			)
		)
		(property "Datasheet" "https://us.schurter.com/pdf/english/typ_UST_1206.pdf"
			(at 0 0 270)
			(layer "F.Fab")
			(hide yes)
			(effects
				(font
					(size 1.27 1.27)
					(thickness 0.15)
				)
			)
		)
		(property "Description" "7 A 32 V AC 63 V DC Fuse Board Mount (Cartridge Style Excluded) Surface Mount 1206 (3216 Metric)"
			(at 0 0 270)
			(layer "F.Fab")
			(hide yes)
			(effects
				(font
					(size 1.27 1.27)
					(thickness 0.15)
				)
			)
		)
		(property "Manufacturer" "Schurter"
			(at 0 0 270)
			(unlocked yes)
			(layer "B.Fab")
			(hide yes)
			(effects
				(font
					(size 1 1)
					(thickness 0.15)
				)
				(justify mirror)
			)
		)
		(property "MPN" "3413.0326.11"
			(at 0 0 270)
			(unlocked yes)
			(layer "B.Fab")
			(hide yes)
			(effects
				(font
					(size 1 1)
					(thickness 0.15)
				)
				(justify mirror)
			)
		)
		(property "Author" "Antmicro"
			(at 0 0 270)
			(unlocked yes)
			(layer "B.Fab")
			(hide yes)
			(effects
				(font
					(size 1 1)
					(thickness 0.15)
				)
				(justify mirror)
			)
		)
		(property "License" "Apache-2.0"
			(at 0 0 270)
			(unlocked yes)
			(layer "B.Fab")
			(hide yes)
			(effects
				(font
					(size 1 1)
					(thickness 0.15)
				)
				(justify mirror)
			)
		)
		(sheetname "/DC-DC Converters/")
		(sheetfile "dc-dc_converters.kicad_sch")
		(attr smd)
		(fp_line
			(start -0.8 0.899)
			(end 0.8 0.899)
			(stroke
				(width 0.15)
				(type solid)
			)
			(layer "B.SilkS")
		)
		(fp_line
			(start -0.8 -0.901)
			(end 0.8 -0.901)
			(stroke
				(width 0.15)
				(type solid)
			)
			(layer "B.SilkS")
		)
		(fp_rect
			(start -2.325 1.15)
			(end 2.325 -1.15)
			(stroke
				(width 0.05)
				(type default)
			)
			(fill no)
			(layer "B.CrtYd")
		)
		(fp_line
			(start -1.677 0.861)
			(end -1.677 -0.792)
			(stroke
				(width 0.15)
				(type solid)
			)
			(layer "B.Fab")
		)
		(fp_line
			(start 1.624 0.861)
			(end -1.677 0.861)
			(stroke
				(width 0.15)
				(type solid)
			)
			(layer "B.Fab")
		)
		(fp_line
			(start -1.677 -0.792)
			(end 1.624 -0.792)
			(stroke
				(width 0.15)
				(type solid)
			)
			(layer "B.Fab")
		)
		(fp_line
			(start 1.624 -0.792)
			(end 1.624 0.861)
			(stroke
				(width 0.15)
				(type solid)
			)
			(layer "B.Fab")
		)
		(pad "1" smd roundrect
			(at -1.5 -0.001 270)
			(size 1.15 1.8)
			(layers "B.Cu" "B.Mask" "B.Paste")
			(roundrect_rratio 0.25)
			(net 5 "+12V")
			(pintype "passive")
		)
		(pad "2" smd roundrect
			(at 1.5 -0.001 270)
			(size 1.15 1.8)
			(layers "B.Cu" "B.Mask" "B.Paste")
			(roundrect_rratio 0.25)
			(net 26 "Net-(D5-C)")
			(pintype "passive")
		)
	)
	(footprint "antmicro-footprints:C_0805_2012Metric"
		(layer "B.Cu")
		(at 94.35 93.05 -90)
		(descr "Capacitor SMD 0805")
		(tags "capacitor SMD 0805")
		(property "Reference" "C35"
			(at -20.279 10.274 180)
			(layer "B.SilkS")
			(effects
				(font
					(size 0.7 0.7)
					(thickness 0.15)
				)
				(justify left bottom mirror)
			)
		)
		(property "Value" "C_22u_25V_0805"
			(at -2.055717 -1.963152 90)
			(layer "B.Fab")
			(effects
				(font
					(size 0.7 0.7)
					(thickness 0.15)
				)
				(justify left bottom mirror)
			)
		)
		(property "Datasheet" "https://product.samsungsem.com/mlcc/CL21A226MAYNNN.do"
			(at 0 0 270)
			(layer "F.Fab")
			(hide yes)
			(effects
				(font
					(size 1.27 1.27)
					(thickness 0.15)
				)
			)
		)
		(property "Description" "SMT Multilayer Ceramic Capacitor, 22uF, +/-20%, 25V, X5R, 0805 [2012 Metric]"
			(at 0 0 270)
			(layer "F.Fab")
			(hide yes)
			(effects
				(font
					(size 1.27 1.27)
					(thickness 0.15)
				)
			)
		)
		(property "MPN" "CL21A226MAYNNNE"
			(at 0 0 270)
			(unlocked yes)
			(layer "B.Fab")
			(hide yes)
			(effects
				(font
					(size 1 1)
					(thickness 0.15)
				)
				(justify mirror)
			)
		)
		(property "Manufacturer" "Samsung Electro-Mechanics"
			(at 0 0 270)
			(unlocked yes)
			(layer "B.Fab")
			(hide yes)
			(effects
				(font
					(size 1 1)
					(thickness 0.15)
				)
				(justify mirror)
			)
		)
		(property "License" "Apache-2.0"
			(at 0 0 270)
			(unlocked yes)
			(layer "B.Fab")
			(hide yes)
			(effects
				(font
					(size 1 1)
					(thickness 0.15)
				)
				(justify mirror)
			)
		)
		(property "Author" "Antmicro"
			(at 0 0 270)
			(unlocked yes)
			(layer "B.Fab")
			(hide yes)
			(effects
				(font
					(size 1 1)
					(thickness 0.15)
				)
				(justify mirror)
			)
		)
		(property "Val" "22u"
			(at 0 0 270)
			(unlocked yes)
			(layer "B.Fab")
			(hide yes)
			(effects
				(font
					(size 1 1)
					(thickness 0.15)
				)
				(justify mirror)
			)
		)
		(property "Voltage" "25V"
			(at 0 0 270)
			(unlocked yes)
			(layer "B.Fab")
			(hide yes)
			(effects
				(font
					(size 1 1)
					(thickness 0.15)
				)
				(justify mirror)
			)
		)
		(property "Dielectric" "X5R"
			(at 0 0 270)
			(unlocked yes)
			(layer "B.Fab")
			(hide yes)
			(effects
				(font
					(size 1 1)
					(thickness 0.15)
				)
				(justify mirror)
			)
		)
		(property "Public" "False"
			(at 0 0 270)
			(unlocked yes)
			(layer "B.Fab")
			(hide yes)
			(effects
				(font
					(size 1 1)
					(thickness 0.15)
				)
				(justify mirror)
			)
		)
		(sheetname "/DC-DC Converters/")
		(sheetfile "dc-dc_converters.kicad_sch")
		(attr smd)
		(fp_line
			(start 0.3 0.7)
			(end -0.3 0.7)
			(stroke
				(width 0.15)
				(type solid)
			)
			(layer "B.SilkS")
		)
		(fp_line
			(start 0.3 -0.7)
			(end -0.3 -0.7)
			(stroke
				(width 0.15)
				(type solid)
			)
			(layer "B.SilkS")
		)
		(fp_rect
			(start 1.95 0.9)
			(end -1.95 -0.9)
			(stroke
				(width 0.05)
				(type default)
			)
			(fill no)
			(layer "B.CrtYd")
		)
		(fp_rect
			(start -0.95 0.675)
			(end 0.95 -0.675)
			(stroke
				(width 0.15)
				(type solid)
			)
			(fill no)
			(layer "B.Fab")
		)
		(pad "1" smd roundrect
			(at -1.1 0 270)
			(size 1.2 1.3)
			(layers "B.Cu" "B.Mask" "B.Paste")
			(roundrect_rratio 0.25)
			(net 2 "GND")
			(pintype "passive")
		)
		(pad "2" smd roundrect
			(at 1.1 0 270)
			(size 1.2 1.3)
			(layers "B.Cu" "B.Mask" "B.Paste")
			(roundrect_rratio 0.25)
			(net 5 "+12V")
			(pintype "passive")
		)
	)
	(footprint "antmicro-footprints:C_0805_2012Metric"
		(layer "B.Cu")
		(at 101.55 98.2 90)
		(descr "Capacitor SMD 0805")
		(tags "capacitor SMD 0805")
		(property "Reference" "C33"
			(at 1.807 -0.458 180)
			(layer "B.SilkS")
			(effects
				(font
					(size 0.7 0.7)
					(thickness 0.15)
				)
				(justify right bottom mirror)
			)
		)
		(property "Value" "C_22u_25V_0805"
			(at -2.055717 -1.963152 90)
			(layer "B.Fab")
			(effects
				(font
					(size 0.7 0.7)
					(thickness 0.15)
				)
				(justify right bottom mirror)
			)
		)
		(property "Datasheet" "https://product.samsungsem.com/mlcc/CL21A226MAYNNN.do"
			(at 0 0 90)
			(layer "F.Fab")
			(hide yes)
			(effects
				(font
					(size 1.27 1.27)
					(thickness 0.15)
				)
			)
		)
		(property "Description" "SMT Multilayer Ceramic Capacitor, 22uF, +/-20%, 25V, X5R, 0805 [2012 Metric]"
			(at 0 0 90)
			(layer "F.Fab")
			(hide yes)
			(effects
				(font
					(size 1.27 1.27)
					(thickness 0.15)
				)
			)
		)
		(property "MPN" "CL21A226MAYNNNE"
			(at 0 0 90)
			(unlocked yes)
			(layer "B.Fab")
			(hide yes)
			(effects
				(font
					(size 1 1)
					(thickness 0.15)
				)
				(justify mirror)
			)
		)
		(property "Manufacturer" "Samsung Electro-Mechanics"
			(at 0 0 90)
			(unlocked yes)
			(layer "B.Fab")
			(hide yes)
			(effects
				(font
					(size 1 1)
					(thickness 0.15)
				)
				(justify mirror)
			)
		)
		(property "License" "Apache-2.0"
			(at 0 0 90)
			(unlocked yes)
			(layer "B.Fab")
			(hide yes)
			(effects
				(font
					(size 1 1)
					(thickness 0.15)
				)
				(justify mirror)
			)
		)
		(property "Author" "Antmicro"
			(at 0 0 90)
			(unlocked yes)
			(layer "B.Fab")
			(hide yes)
			(effects
				(font
					(size 1 1)
					(thickness 0.15)
				)
				(justify mirror)
			)
		)
		(property "Val" "22u"
			(at 0 0 90)
			(unlocked yes)
			(layer "B.Fab")
			(hide yes)
			(effects
				(font
					(size 1 1)
					(thickness 0.15)
				)
				(justify mirror)
			)
		)
		(property "Voltage" "25V"
			(at 0 0 90)
			(unlocked yes)
			(layer "B.Fab")
			(hide yes)
			(effects
				(font
					(size 1 1)
					(thickness 0.15)
				)
				(justify mirror)
			)
		)
		(property "Dielectric" "X5R"
			(at 0 0 90)
			(unlocked yes)
			(layer "B.Fab")
			(hide yes)
			(effects
				(font
					(size 1 1)
					(thickness 0.15)
				)
				(justify mirror)
			)
		)
		(property "Public" "False"
			(at 0 0 90)
			(unlocked yes)
			(layer "B.Fab")
			(hide yes)
			(effects
				(font
					(size 1 1)
					(thickness 0.15)
				)
				(justify mirror)
			)
		)
		(sheetname "/DC-DC Converters/")
		(sheetfile "dc-dc_converters.kicad_sch")
		(attr smd)
		(fp_line
			(start 0.3 -0.7)
			(end -0.3 -0.7)
			(stroke
				(width 0.15)
				(type solid)
			)
			(layer "B.SilkS")
		)
		(fp_line
			(start 0.3 0.7)
			(end -0.3 0.7)
			(stroke
				(width 0.15)
				(type solid)
			)
			(layer "B.SilkS")
		)
		(fp_rect
			(start 1.95 0.9)
			(end -1.95 -0.9)
			(stroke
				(width 0.05)
				(type default)
			)
			(fill no)
			(layer "B.CrtYd")
		)
		(fp_rect
			(start -0.95 0.675)
			(end 0.95 -0.675)
			(stroke
				(width 0.15)
				(type solid)
			)
			(fill no)
			(layer "B.Fab")
		)
		(pad "1" smd roundrect
			(at -1.1 0 90)
			(size 1.2 1.3)
			(layers "B.Cu" "B.Mask" "B.Paste")
			(roundrect_rratio 0.25)
			(net 2 "GND")
			(pintype "passive")
		)
		(pad "2" smd roundrect
			(at 1.1 0 90)
			(size 1.2 1.3)
			(layers "B.Cu" "B.Mask" "B.Paste")
			(roundrect_rratio 0.25)
			(net 5 "+12V")
			(pintype "passive")
		)
	)
)
